(kicad_pcb
	(version 20260206)
	(generator "pcbnew")
	(generator_version "10.0")
	(general
		(thickness 1.6)
		(legacy_teardrops no)
	)
	(paper "A4")
	(title_block
		(title "peb — Lightning_PEB_BRD.brd")
		(comment 1 "Lightning (Wiwynn / Facebook NVMe JBOF) / footprints 1543-1549 of 2563")
	)
	(layers
		(0 "F.Cu" signal "TOP")
		(4 "In1.Cu" signal "L2GND")
		(6 "In2.Cu" signal "L3")
		(8 "In3.Cu" signal "L4VCC")
		(10 "In4.Cu" signal "L5VCC")
		(12 "In5.Cu" signal "L6")
		(14 "In6.Cu" signal "L7GND")
		(2 "B.Cu" signal "BOTTOM")
		(9 "F.Adhes" user "F.Adhesive")
		(11 "B.Adhes" user "B.Adhesive")
		(13 "F.Paste" user "Package Geometry/Pastemask Top")
		(15 "B.Paste" user "Package Geometry/Pastemask Bottom")
		(5 "F.SilkS" user "Ref Des/Silkscreen Top")
		(7 "B.SilkS" user "Ref Des/Silkscreen Bottom")
		(1 "F.Mask" user "Board Geometry/Soldermask Top")
		(3 "B.Mask" user "Board Geometry/Soldermask Bottom")
		(17 "Dwgs.User" user "User.Drawings")
		(19 "Cmts.User" user "User.Comments")
		(21 "Eco1.User" user "User.Eco1")
		(23 "Eco2.User" user "User.Eco2")
		(25 "Edge.Cuts" user "Board Geometry/Outline")
		(27 "Margin" user)
		(31 "F.CrtYd" user "Package Geometry/Place Bound Top")
		(29 "B.CrtYd" user "Package Geometry/Place Bound Bottom")
		(35 "F.Fab" user "Ref Des/Assembly Top")
		(33 "B.Fab" user "Ref Des/Assembly Bottom")
	)
	(footprint ""
		(layer "F.Cu")
		(at 17.43456 -133.92658 -90)
		(property "Reference" "R685"
			(at 0 0 270)
			(layer "F.SilkS")
			(hide yes)
			(effects
				(font
					(size 1.27 1.27)
				)
			)
		)
		(property "Value" "0R2J-2-GP"
			(at 0.064008 -3.993896 270)
			(unlocked yes)
			(layer "F.Fab")
			(hide yes)
			(effects
				(font
					(size 1.016 1.016)
					(thickness 0.1524)
				)
			)
		)
		(property "Device Type" "R402H16"
			(at 0.064008 -5.517896 270)
			(unlocked yes)
			(layer "F.Fab")
			(hide yes)
			(effects
				(font
					(size 1.016 1.016)
					(thickness 0.1524)
				)
			)
		)
		(duplicate_pad_numbers_are_jumpers no)
		(fp_line
			(start -0.508 -0.9398)
			(end -0.508 0.9398)
			(stroke
				(width 0.1524)
				(type default)
			)
			(layer "F.SilkS")
		)
		(fp_line
			(start 0.508 -0.9398)
			(end -0.508 -0.9398)
			(stroke
				(width 0.1524)
				(type default)
			)
			(layer "F.SilkS")
		)
		(fp_rect
			(start -0.508 0.9398)
			(end 0.508 -0.9398)
			(stroke
				(width 0)
				(type default)
			)
			(fill no)
			(layer "F.CrtYd")
		)
		(fp_rect
			(start -0.508 0.9398)
			(end 0.508 -0.9398)
			(stroke
				(width 0)
				(type default)
			)
			(fill no)
			(layer "F.Fab")
		)
		(pad "1" smd custom
			(at 0 -0.4445 270)
			(size 0.1397 0.1397)
			(layers "F.Cu" "F.Mask" "F.Paste")
			(net "GPIOS5_R")
			(options
				(clearance outline)
				(anchor circle)
			)
			(primitives
				(gr_poly
					(pts
						(arc
							(start -0.1778 -0.2794)
							(mid -0.249642 -0.249642)
							(end -0.2794 -0.1778)
						)
						(arc
							(start -0.2794 0.1778)
							(mid -0.249642 0.249642)
							(end -0.1778 0.2794)
						)
						(arc
							(start 0.1778 0.2794)
							(mid 0.249642 0.249642)
							(end 0.2794 0.1778)
						)
						(arc
							(start 0.2794 -0.1778)
							(mid 0.249642 -0.249642)
							(end 0.1778 -0.2794)
						)
					)
					(width 0)
					(fill yes)
				)
			)
		)
		(pad "2" smd custom
			(at 0 0.4445 270)
			(size 0.1397 0.1397)
			(layers "F.Cu" "F.Mask" "F.Paste")
			(net "TRAY_ID0")
			(options
				(clearance outline)
				(anchor circle)
			)
			(primitives
				(gr_poly
					(pts
						(arc
							(start -0.1778 -0.2794)
							(mid -0.249642 -0.249642)
							(end -0.2794 -0.1778)
						)
						(arc
							(start -0.2794 0.1778)
							(mid -0.249642 0.249642)
							(end -0.1778 0.2794)
						)
						(arc
							(start 0.1778 0.2794)
							(mid 0.249642 0.249642)
							(end 0.2794 0.1778)
						)
						(arc
							(start 0.2794 -0.1778)
							(mid 0.249642 -0.249642)
							(end 0.1778 -0.2794)
						)
					)
					(width 0)
					(fill yes)
				)
			)
		)
	)
	(footprint ""
		(layer "F.Cu")
		(at 154.1018 -88.4428 90)
		(property "Reference" "R3110"
			(at 0 0 90)
			(layer "F.SilkS")
			(hide yes)
			(effects
				(font
					(size 1.27 1.27)
				)
			)
		)
		(property "Value" "33R2F-3-GP"
			(at 0.064008 -3.993896 90)
			(unlocked yes)
			(layer "F.Fab")
			(hide yes)
			(effects
				(font
					(size 1.016 1.016)
					(thickness 0.1524)
				)
			)
		)
		(property "Device Type" "R402H16"
			(at 0.064008 -5.517896 90)
			(unlocked yes)
			(layer "F.Fab")
			(hide yes)
			(effects
				(font
					(size 1.016 1.016)
					(thickness 0.1524)
				)
			)
		)
		(duplicate_pad_numbers_are_jumpers no)
		(fp_line
			(start 0.508 -0.9398)
			(end -0.508 -0.9398)
			(stroke
				(width 0.1524)
				(type default)
			)
			(layer "F.SilkS")
		)
		(fp_line
			(start -0.508 -0.9398)
			(end -0.508 0.9398)
			(stroke
				(width 0.1524)
				(type default)
			)
			(layer "F.SilkS")
		)
		(fp_rect
			(start -0.508 0.9398)
			(end 0.508 -0.9398)
			(stroke
				(width 0)
				(type default)
			)
			(fill no)
			(layer "F.CrtYd")
		)
		(fp_rect
			(start -0.508 0.9398)
			(end 0.508 -0.9398)
			(stroke
				(width 0)
				(type default)
			)
			(fill no)
			(layer "F.Fab")
		)
		(pad "1" smd custom
			(at 0 -0.4445 90)
			(size 0.1397 0.1397)
			(layers "F.Cu" "F.Mask" "F.Paste")
			(net "CLKGNE_SADR_R")
			(options
				(clearance outline)
				(anchor circle)
			)
			(primitives
				(gr_poly
					(pts
						(arc
							(start -0.1778 -0.2794)
							(mid -0.249642 -0.249642)
							(end -0.2794 -0.1778)
						)
						(arc
							(start -0.2794 0.1778)
							(mid -0.249642 0.249642)
							(end -0.1778 0.2794)
						)
						(arc
							(start 0.1778 0.2794)
							(mid 0.249642 0.249642)
							(end 0.2794 0.1778)
						)
						(arc
							(start 0.2794 -0.1778)
							(mid 0.249642 -0.249642)
							(end 0.1778 -0.2794)
						)
					)
					(width 0)
					(fill yes)
				)
			)
		)
		(pad "2" smd custom
			(at 0 0.4445 90)
			(size 0.1397 0.1397)
			(layers "F.Cu" "F.Mask" "F.Paste")
			(net "CLKGNE_SADR")
			(options
				(clearance outline)
				(anchor circle)
			)
			(primitives
				(gr_poly
					(pts
						(arc
							(start -0.1778 -0.2794)
							(mid -0.249642 -0.249642)
							(end -0.2794 -0.1778)
						)
						(arc
							(start -0.2794 0.1778)
							(mid -0.249642 0.249642)
							(end -0.1778 0.2794)
						)
						(arc
							(start 0.1778 0.2794)
							(mid 0.249642 0.249642)
							(end 0.2794 0.1778)
						)
						(arc
							(start 0.2794 -0.1778)
							(mid 0.249642 -0.249642)
							(end 0.1778 -0.2794)
						)
					)
					(width 0)
					(fill yes)
				)
			)
		)
	)
	(footprint ""
		(layer "F.Cu")
		(at 132.310124 -208.889092 180)
		(property "Reference" "R7971"
			(at 0 0 180)
			(layer "F.SilkS")
			(hide yes)
			(effects
				(font
					(size 1.27 1.27)
				)
			)
		)
		(property "Value" "0R2J-2-GP"
			(at 0.064008 -3.993896 180)
			(unlocked yes)
			(layer "F.Fab")
			(hide yes)
			(effects
				(font
					(size 1.016 1.016)
					(thickness 0.1524)
				)
			)
		)
		(property "Device Type" "R402H16"
			(at 0.064008 -5.517896 180)
			(unlocked yes)
			(layer "F.Fab")
			(hide yes)
			(effects
				(font
					(size 1.016 1.016)
					(thickness 0.1524)
				)
			)
		)
		(duplicate_pad_numbers_are_jumpers no)
		(fp_line
			(start 0.508 -0.9398)
			(end -0.508 -0.9398)
			(stroke
				(width 0.1524)
				(type default)
			)
			(layer "F.SilkS")
		)
		(fp_line
			(start -0.508 -0.9398)
			(end -0.508 0.9398)
			(stroke
				(width 0.1524)
				(type default)
			)
			(layer "F.SilkS")
		)
		(fp_rect
			(start -0.508 0.9398)
			(end 0.508 -0.9398)
			(stroke
				(width 0)
				(type default)
			)
			(fill no)
			(layer "F.CrtYd")
		)
		(fp_rect
			(start -0.508 0.9398)
			(end 0.508 -0.9398)
			(stroke
				(width 0)
				(type default)
			)
			(fill no)
			(layer "F.Fab")
		)
		(pad "1" smd custom
			(at 0 -0.4445 180)
			(size 0.1397 0.1397)
			(layers "F.Cu" "F.Mask" "F.Paste")
			(net "SSD_PERST#6")
			(options
				(clearance outline)
				(anchor circle)
			)
			(primitives
				(gr_poly
					(pts
						(arc
							(start -0.1778 -0.2794)
							(mid -0.249642 -0.249642)
							(end -0.2794 -0.1778)
						)
						(arc
							(start -0.2794 0.1778)
							(mid -0.249642 0.249642)
							(end -0.1778 0.2794)
						)
						(arc
							(start 0.1778 0.2794)
							(mid 0.249642 0.249642)
							(end 0.2794 0.1778)
						)
						(arc
							(start 0.2794 -0.1778)
							(mid 0.249642 -0.249642)
							(end 0.1778 -0.2794)
						)
					)
					(width 0)
					(fill yes)
				)
			)
		)
		(pad "2" smd custom
			(at 0 0.4445 180)
			(size 0.1397 0.1397)
			(layers "F.Cu" "F.Mask" "F.Paste")
			(net "SSD_PERST#6_R")
			(options
				(clearance outline)
				(anchor circle)
			)
			(primitives
				(gr_poly
					(pts
						(arc
							(start -0.1778 -0.2794)
							(mid -0.249642 -0.249642)
							(end -0.2794 -0.1778)
						)
						(arc
							(start -0.2794 0.1778)
							(mid -0.249642 0.249642)
							(end -0.1778 0.2794)
						)
						(arc
							(start 0.1778 0.2794)
							(mid 0.249642 0.249642)
							(end 0.2794 0.1778)
						)
						(arc
							(start 0.2794 -0.1778)
							(mid 0.249642 -0.249642)
							(end 0.1778 -0.2794)
						)
					)
					(width 0)
					(fill yes)
				)
			)
		)
	)
	(footprint ""
		(layer "F.Cu")
		(at 268.351 -12.3698 -90)
		(property "Reference" "R7904"
			(at 0 0 270)
			(layer "F.SilkS")
			(hide yes)
			(effects
				(font
					(size 1.27 1.27)
				)
			)
		)
		(property "Value" "0R2J-2-GP"
			(at 0.064008 -3.993896 270)
			(unlocked yes)
			(layer "F.Fab")
			(hide yes)
			(effects
				(font
					(size 1.016 1.016)
					(thickness 0.1524)
				)
			)
		)
		(property "Device Type" "R402H16"
			(at 0.064008 -5.517896 270)
			(unlocked yes)
			(layer "F.Fab")
			(hide yes)
			(effects
				(font
					(size 1.016 1.016)
					(thickness 0.1524)
				)
			)
		)
		(duplicate_pad_numbers_are_jumpers no)
		(fp_line
			(start -0.508 -0.9398)
			(end -0.508 0.9398)
			(stroke
				(width 0.1524)
				(type default)
			)
			(layer "F.SilkS")
		)
		(fp_line
			(start 0.508 -0.9398)
			(end -0.508 -0.9398)
			(stroke
				(width 0.1524)
				(type default)
			)
			(layer "F.SilkS")
		)
		(fp_rect
			(start -0.508 0.9398)
			(end 0.508 -0.9398)
			(stroke
				(width 0)
				(type default)
			)
			(fill no)
			(layer "F.CrtYd")
		)
		(fp_rect
			(start -0.508 0.9398)
			(end 0.508 -0.9398)
			(stroke
				(width 0)
				(type default)
			)
			(fill no)
			(layer "F.Fab")
		)
		(pad "1" smd custom
			(at 0 -0.4445 270)
			(size 0.1397 0.1397)
			(layers "F.Cu" "F.Mask" "F.Paste")
			(net "PM8536_RST#_LS")
			(options
				(clearance outline)
				(anchor circle)
			)
			(primitives
				(gr_poly
					(pts
						(arc
							(start -0.1778 -0.2794)
							(mid -0.249642 -0.249642)
							(end -0.2794 -0.1778)
						)
						(arc
							(start -0.2794 0.1778)
							(mid -0.249642 0.249642)
							(end -0.1778 0.2794)
						)
						(arc
							(start 0.1778 0.2794)
							(mid 0.249642 0.249642)
							(end 0.2794 0.1778)
						)
						(arc
							(start 0.2794 -0.1778)
							(mid 0.249642 -0.249642)
							(end 0.1778 -0.2794)
						)
					)
					(width 0)
					(fill yes)
				)
			)
		)
		(pad "2" smd custom
			(at 0 0.4445 270)
			(size 0.1397 0.1397)
			(layers "F.Cu" "F.Mask" "F.Paste")
			(net "PM8536_RST#_LS_R")
			(options
				(clearance outline)
				(anchor circle)
			)
			(primitives
				(gr_poly
					(pts
						(arc
							(start -0.1778 -0.2794)
							(mid -0.249642 -0.249642)
							(end -0.2794 -0.1778)
						)
						(arc
							(start -0.2794 0.1778)
							(mid -0.249642 0.249642)
							(end -0.1778 0.2794)
						)
						(arc
							(start 0.1778 0.2794)
							(mid 0.249642 0.249642)
							(end 0.2794 0.1778)
						)
						(arc
							(start 0.2794 -0.1778)
							(mid 0.249642 -0.249642)
							(end 0.1778 -0.2794)
						)
					)
					(width 0)
					(fill yes)
				)
			)
		)
	)
	(footprint ""
		(layer "F.Cu")
		(at 71.3994 -52.5272 180)
		(property "Reference" "R960"
			(at 0 0 180)
			(layer "F.SilkS")
			(hide yes)
			(effects
				(font
					(size 1.27 1.27)
				)
			)
		)
		(property "Value" "4K7R2F-GP"
			(at 0.064008 -3.993896 180)
			(unlocked yes)
			(layer "F.Fab")
			(hide yes)
			(effects
				(font
					(size 1.016 1.016)
					(thickness 0.1524)
				)
			)
		)
		(property "Device Type" "R402H16"
			(at 0.064008 -5.517896 180)
			(unlocked yes)
			(layer "F.Fab")
			(hide yes)
			(effects
				(font
					(size 1.016 1.016)
					(thickness 0.1524)
				)
			)
		)
		(duplicate_pad_numbers_are_jumpers no)
		(fp_line
			(start 0.508 -0.9398)
			(end -0.508 -0.9398)
			(stroke
				(width 0.1524)
				(type default)
			)
			(layer "F.SilkS")
		)
		(fp_line
			(start -0.508 -0.9398)
			(end -0.508 0.9398)
			(stroke
				(width 0.1524)
				(type default)
			)
			(layer "F.SilkS")
		)
		(fp_rect
			(start -0.508 0.9398)
			(end 0.508 -0.9398)
			(stroke
				(width 0)
				(type default)
			)
			(fill no)
			(layer "F.CrtYd")
		)
		(fp_rect
			(start -0.508 0.9398)
			(end 0.508 -0.9398)
			(stroke
				(width 0)
				(type default)
			)
			(fill no)
			(layer "F.Fab")
		)
		(pad "1" smd custom
			(at 0 -0.4445 180)
			(size 0.1397 0.1397)
			(layers "F.Cu" "F.Mask" "F.Paste")
			(net "BMC_CPU_EN")
			(options
				(clearance outline)
				(anchor circle)
			)
			(primitives
				(gr_poly
					(pts
						(arc
							(start -0.1778 -0.2794)
							(mid -0.249642 -0.249642)
							(end -0.2794 -0.1778)
						)
						(arc
							(start -0.2794 0.1778)
							(mid -0.249642 0.249642)
							(end -0.1778 0.2794)
						)
						(arc
							(start 0.1778 0.2794)
							(mid 0.249642 0.249642)
							(end 0.2794 0.1778)
						)
						(arc
							(start 0.2794 -0.1778)
							(mid 0.249642 -0.249642)
							(end 0.1778 -0.2794)
						)
					)
					(width 0)
					(fill yes)
				)
			)
		)
		(pad "2" smd custom
			(at 0 0.4445 180)
			(size 0.1397 0.1397)
			(layers "F.Cu" "F.Mask" "F.Paste")
			(net "P3V3_STBY")
			(options
				(clearance outline)
				(anchor circle)
			)
			(primitives
				(gr_poly
					(pts
						(arc
							(start -0.1778 -0.2794)
							(mid -0.249642 -0.249642)
							(end -0.2794 -0.1778)
						)
						(arc
							(start -0.2794 0.1778)
							(mid -0.249642 0.249642)
							(end -0.1778 0.2794)
						)
						(arc
							(start 0.1778 0.2794)
							(mid 0.249642 0.249642)
							(end 0.2794 0.1778)
						)
						(arc
							(start 0.2794 -0.1778)
							(mid 0.249642 -0.249642)
							(end 0.1778 -0.2794)
						)
					)
					(width 0)
					(fill yes)
				)
			)
		)
	)
	(footprint ""
		(layer "F.Cu")
		(at 26.0096 -82.3214 90)
		(property "Reference" "R384"
			(at 0 0 90)
			(layer "F.SilkS")
			(hide yes)
			(effects
				(font
					(size 1.27 1.27)
				)
			)
		)
		(property "Value" "0R2J-2-GP"
			(at 0.064008 -3.993896 90)
			(unlocked yes)
			(layer "F.Fab")
			(hide yes)
			(effects
				(font
					(size 1.016 1.016)
					(thickness 0.1524)
				)
			)
		)
		(property "Device Type" "R402H16"
			(at 0.064008 -5.517896 90)
			(unlocked yes)
			(layer "F.Fab")
			(hide yes)
			(effects
				(font
					(size 1.016 1.016)
					(thickness 0.1524)
				)
			)
		)
		(duplicate_pad_numbers_are_jumpers no)
		(fp_line
			(start 0.508 -0.9398)
			(end -0.508 -0.9398)
			(stroke
				(width 0.1524)
				(type default)
			)
			(layer "F.SilkS")
		)
		(fp_line
			(start -0.508 -0.9398)
			(end -0.508 0.9398)
			(stroke
				(width 0.1524)
				(type default)
			)
			(layer "F.SilkS")
		)
		(fp_rect
			(start -0.508 0.9398)
			(end 0.508 -0.9398)
			(stroke
				(width 0)
				(type default)
			)
			(fill no)
			(layer "F.CrtYd")
		)
		(fp_rect
			(start -0.508 0.9398)
			(end 0.508 -0.9398)
			(stroke
				(width 0)
				(type default)
			)
			(fill no)
			(layer "F.Fab")
		)
		(pad "1" smd custom
			(at 0 -0.4445 90)
			(size 0.1397 0.1397)
			(layers "F.Cu" "F.Mask" "F.Paste")
			(net "NVM_SO")
			(options
				(clearance outline)
				(anchor circle)
			)
			(primitives
				(gr_poly
					(pts
						(arc
							(start -0.1778 -0.2794)
							(mid -0.249642 -0.249642)
							(end -0.2794 -0.1778)
						)
						(arc
							(start -0.2794 0.1778)
							(mid -0.249642 0.249642)
							(end -0.1778 0.2794)
						)
						(arc
							(start 0.1778 0.2794)
							(mid 0.249642 0.249642)
							(end 0.2794 0.1778)
						)
						(arc
							(start 0.2794 -0.1778)
							(mid 0.249642 -0.249642)
							(end 0.1778 -0.2794)
						)
					)
					(width 0)
					(fill yes)
				)
			)
		)
		(pad "2" smd custom
			(at 0 0.4445 90)
			(size 0.1397 0.1397)
			(layers "F.Cu" "F.Mask" "F.Paste")
			(net "I210_SO_R")
			(options
				(clearance outline)
				(anchor circle)
			)
			(primitives
				(gr_poly
					(pts
						(arc
							(start -0.1778 -0.2794)
							(mid -0.249642 -0.249642)
							(end -0.2794 -0.1778)
						)
						(arc
							(start -0.2794 0.1778)
							(mid -0.249642 0.249642)
							(end -0.1778 0.2794)
						)
						(arc
							(start 0.1778 0.2794)
							(mid 0.249642 0.249642)
							(end 0.2794 0.1778)
						)
						(arc
							(start 0.2794 -0.1778)
							(mid 0.249642 -0.249642)
							(end 0.1778 -0.2794)
						)
					)
					(width 0)
					(fill yes)
				)
			)
		)
	)
	(footprint ""
		(layer "F.Cu")
		(at 205.844902 -30.200092 -90)
		(property "Reference" "R823"
			(at 0 0 270)
			(layer "F.SilkS")
			(hide yes)
			(effects
				(font
					(size 1.27 1.27)
				)
			)
		)
		(property "Value" "4K7R2F-GP"
			(at 0.064008 -3.993896 270)
			(unlocked yes)
			(layer "F.Fab")
			(hide yes)
			(effects
				(font
					(size 1.016 1.016)
					(thickness 0.1524)
				)
			)
		)
		(property "Device Type" "R402H16"
			(at 0.064008 -5.517896 270)
			(unlocked yes)
			(layer "F.Fab")
			(hide yes)
			(effects
				(font
					(size 1.016 1.016)
					(thickness 0.1524)
				)
			)
		)
		(duplicate_pad_numbers_are_jumpers no)
		(fp_line
			(start -0.508 -0.9398)
			(end -0.508 0.9398)
			(stroke
				(width 0.1524)
				(type default)
			)
			(layer "F.SilkS")
		)
		(fp_line
			(start 0.508 -0.9398)
			(end -0.508 -0.9398)
			(stroke
				(width 0.1524)
				(type default)
			)
			(layer "F.SilkS")
		)
		(fp_rect
			(start -0.508 0.9398)
			(end 0.508 -0.9398)
			(stroke
				(width 0)
				(type default)
			)
			(fill no)
			(layer "F.CrtYd")
		)
		(fp_rect
			(start -0.508 0.9398)
			(end 0.508 -0.9398)
			(stroke
				(width 0)
				(type default)
			)
			(fill no)
			(layer "F.Fab")
		)
		(pad "1" smd custom
			(at 0 -0.4445 270)
			(size 0.1397 0.1397)
			(layers "F.Cu" "F.Mask" "F.Paste")
			(net "P3V3_STBY")
			(options
				(clearance outline)
				(anchor circle)
			)
			(primitives
				(gr_poly
					(pts
						(arc
							(start -0.1778 -0.2794)
							(mid -0.249642 -0.249642)
							(end -0.2794 -0.1778)
						)
						(arc
							(start -0.2794 0.1778)
							(mid -0.249642 0.249642)
							(end -0.1778 0.2794)
						)
						(arc
							(start 0.1778 0.2794)
							(mid 0.249642 0.249642)
							(end 0.2794 0.1778)
						)
						(arc
							(start 0.2794 -0.1778)
							(mid 0.249642 -0.249642)
							(end 0.1778 -0.2794)
						)
					)
					(width 0)
					(fill yes)
				)
			)
		)
		(pad "2" smd custom
			(at 0 0.4445 270)
			(size 0.1397 0.1397)
			(layers "F.Cu" "F.Mask" "F.Paste")
			(net "U55_INT_N")
			(options
				(clearance outline)
				(anchor circle)
			)
			(primitives
				(gr_poly
					(pts
						(arc
							(start -0.1778 -0.2794)
							(mid -0.249642 -0.249642)
							(end -0.2794 -0.1778)
						)
						(arc
							(start -0.2794 0.1778)
							(mid -0.249642 0.249642)
							(end -0.1778 0.2794)
						)
						(arc
							(start 0.1778 0.2794)
							(mid 0.249642 0.249642)
							(end 0.2794 0.1778)
						)
						(arc
							(start 0.2794 -0.1778)
							(mid 0.249642 -0.249642)
							(end 0.1778 -0.2794)
						)
					)
					(width 0)
					(fill yes)
				)
			)
		)
	)
)
